(kicad_pcb
	(version 20260206)
	(generator "pcbnew")
	(generator_version "10.0")
	(general
		(thickness 1.6)
		(legacy_teardrops no)
	)
	(paper "A4")
	(title_block
		(title "fcb — 12433-1M.1206WZS1330.brd")
		(comment 1 "Open Vault / Knox (Wiwynn) / footprints 120-128 of 495")
	)
	(layers
		(0 "F.Cu" signal "TOP")
		(4 "In1.Cu" signal "L2GND")
		(6 "In2.Cu" signal "L3VCC")
		(2 "B.Cu" signal "BOTTOM")
		(9 "F.Adhes" user "F.Adhesive")
		(11 "B.Adhes" user "B.Adhesive")
		(13 "F.Paste" user "Package Geometry/Pastemask Top")
		(15 "B.Paste" user "Package Geometry/Pastemask Bottom")
		(5 "F.SilkS" user "Ref Des/Silkscreen Top")
		(7 "B.SilkS" user "Ref Des/Silkscreen Bottom")
		(1 "F.Mask" user "Board Geometry/Soldermask Top")
		(3 "B.Mask" user "Board Geometry/Soldermask Bottom")
		(17 "Dwgs.User" user "User.Drawings")
		(19 "Cmts.User" user "User.Comments")
		(21 "Eco1.User" user "User.Eco1")
		(23 "Eco2.User" user "User.Eco2")
		(25 "Edge.Cuts" user "Board Geometry/Outline")
		(27 "Margin" user)
		(31 "F.CrtYd" user "Package Geometry/Place Bound Top")
		(29 "B.CrtYd" user "Package Geometry/Place Bound Bottom")
		(35 "F.Fab" user "Ref Des/Assembly Top")
		(33 "B.Fab" user "Ref Des/Assembly Bottom")
	)
	(footprint ""
		(layer "F.Cu")
		(at 37.846 -240.665 180)
		(property "Reference" "R157"
			(at 0 0 180)
			(layer "F.SilkS")
			(hide yes)
			(effects
				(font
					(size 1.27 1.27)
				)
			)
		)
		(property "Value" "330R2J-3-GP"
			(at 0.064008 -3.993896 180)
			(unlocked yes)
			(layer "F.Fab")
			(hide yes)
			(effects
				(font
					(size 1.016 1.016)
					(thickness 0.1524)
				)
			)
		)
		(property "Device Type" "R402H16"
			(at 0.064008 -5.517896 180)
			(unlocked yes)
			(layer "F.Fab")
			(hide yes)
			(effects
				(font
					(size 1.016 1.016)
					(thickness 0.1524)
				)
			)
		)
		(duplicate_pad_numbers_are_jumpers no)
		(fp_line
			(start 0.508 -0.9398)
			(end -0.508 -0.9398)
			(stroke
				(width 0.1524)
				(type default)
			)
			(layer "F.SilkS")
		)
		(fp_line
			(start -0.508 -0.9398)
			(end -0.508 0.9398)
			(stroke
				(width 0.1524)
				(type default)
			)
			(layer "F.SilkS")
		)
		(fp_rect
			(start -0.508 0.9398)
			(end 0.508 -0.9398)
			(stroke
				(width 0)
				(type default)
			)
			(fill no)
			(layer "F.CrtYd")
		)
		(fp_rect
			(start -0.508 0.9398)
			(end 0.508 -0.9398)
			(stroke
				(width 0)
				(type default)
			)
			(fill no)
			(layer "F.Fab")
		)
		(pad "1" smd custom
			(at 0 -0.4445 180)
			(size 0.1397 0.1397)
			(layers "F.Cu" "F.Mask" "F.Paste")
			(net "P3V3")
			(options
				(clearance outline)
				(anchor circle)
			)
			(primitives
				(gr_poly
					(pts
						(arc
							(start -0.1778 -0.2794)
							(mid -0.249642 -0.249642)
							(end -0.2794 -0.1778)
						)
						(arc
							(start -0.2794 0.1778)
							(mid -0.249642 0.249642)
							(end -0.1778 0.2794)
						)
						(arc
							(start 0.1778 0.2794)
							(mid 0.249642 0.249642)
							(end 0.2794 0.1778)
						)
						(arc
							(start 0.2794 -0.1778)
							(mid 0.249642 -0.249642)
							(end 0.1778 -0.2794)
						)
					)
					(width 0)
					(fill yes)
				)
			)
		)
		(pad "2" smd custom
			(at 0 0.4445 180)
			(size 0.1397 0.1397)
			(layers "F.Cu" "F.Mask" "F.Paste")
			(net "LED_DR_LED1")
			(options
				(clearance outline)
				(anchor circle)
			)
			(primitives
				(gr_poly
					(pts
						(arc
							(start -0.1778 -0.2794)
							(mid -0.249642 -0.249642)
							(end -0.2794 -0.1778)
						)
						(arc
							(start -0.2794 0.1778)
							(mid -0.249642 0.249642)
							(end -0.1778 0.2794)
						)
						(arc
							(start 0.1778 0.2794)
							(mid 0.249642 0.249642)
							(end 0.2794 0.1778)
						)
						(arc
							(start 0.2794 -0.1778)
							(mid 0.249642 -0.249642)
							(end 0.1778 -0.2794)
						)
					)
					(width 0)
					(fill yes)
				)
			)
		)
	)
	(footprint ""
		(layer "F.Cu")
		(at 29.7434 -363.2454 -90)
		(property "Reference" "TP22"
			(at 0 0 270)
			(layer "F.SilkS")
			(hide yes)
			(effects
				(font
					(size 1.27 1.27)
				)
			)
		)
		(property "Value" "TPAD32-GP"
			(at 0 -3.166364 270)
			(unlocked yes)
			(layer "F.Fab")
			(hide yes)
			(effects
				(font
					(size 1.016 1.016)
					(thickness 0.1524)
				)
			)
		)
		(property "Device Type" "TPAD32"
			(at 0 -4.690618 270)
			(unlocked yes)
			(layer "F.Fab")
			(hide yes)
			(effects
				(font
					(size 1.016 1.016)
					(thickness 0.1524)
				)
			)
		)
		(duplicate_pad_numbers_are_jumpers no)
		(fp_poly
			(pts
				(arc
					(start 0 -0.7112)
					(mid 0 0.7112)
					(end 0 -0.7112)
				)
			)
			(stroke
				(width 0)
				(type default)
			)
			(fill no)
			(layer "F.CrtYd")
		)
		(fp_poly
			(pts
				(arc
					(start 0 -0.7112)
					(mid 0 0.7112)
					(end 0 -0.7112)
				)
			)
			(stroke
				(width 0)
				(type default)
			)
			(fill no)
			(layer "F.Fab")
		)
		(pad "1" smd circle
			(at 0 0 270)
			(size 0.8128 0.8128)
			(layers "F.Cu" "F.Mask" "F.Paste")
			(net "ADM1276_GPIO2")
		)
	)
	(footprint ""
		(layer "F.Cu")
		(at 22.733 -179.8066 -90)
		(property "Reference" "R83"
			(at 0 0 270)
			(layer "F.SilkS")
			(hide yes)
			(effects
				(font
					(size 1.27 1.27)
				)
			)
		)
		(property "Value" "4K7R2F-GP"
			(at 0.064008 -3.993896 270)
			(unlocked yes)
			(layer "F.Fab")
			(hide yes)
			(effects
				(font
					(size 1.016 1.016)
					(thickness 0.1524)
				)
			)
		)
		(property "Device Type" "R402H16"
			(at 0.064008 -5.517896 270)
			(unlocked yes)
			(layer "F.Fab")
			(hide yes)
			(effects
				(font
					(size 1.016 1.016)
					(thickness 0.1524)
				)
			)
		)
		(duplicate_pad_numbers_are_jumpers no)
		(fp_line
			(start -0.508 -0.9398)
			(end -0.508 0.9398)
			(stroke
				(width 0.1524)
				(type default)
			)
			(layer "F.SilkS")
		)
		(fp_line
			(start 0.508 -0.9398)
			(end -0.508 -0.9398)
			(stroke
				(width 0.1524)
				(type default)
			)
			(layer "F.SilkS")
		)
		(fp_rect
			(start -0.508 0.9398)
			(end 0.508 -0.9398)
			(stroke
				(width 0)
				(type default)
			)
			(fill no)
			(layer "F.CrtYd")
		)
		(fp_rect
			(start -0.508 0.9398)
			(end 0.508 -0.9398)
			(stroke
				(width 0)
				(type default)
			)
			(fill no)
			(layer "F.Fab")
		)
		(pad "1" smd custom
			(at 0 -0.4445 270)
			(size 0.1397 0.1397)
			(layers "F.Cu" "F.Mask" "F.Paste")
			(net "P12V")
			(options
				(clearance outline)
				(anchor circle)
			)
			(primitives
				(gr_poly
					(pts
						(arc
							(start -0.1778 -0.2794)
							(mid -0.249642 -0.249642)
							(end -0.2794 -0.1778)
						)
						(arc
							(start -0.2794 0.1778)
							(mid -0.249642 0.249642)
							(end -0.1778 0.2794)
						)
						(arc
							(start 0.1778 0.2794)
							(mid 0.249642 0.249642)
							(end 0.2794 0.1778)
						)
						(arc
							(start 0.2794 -0.1778)
							(mid 0.249642 -0.249642)
							(end 0.1778 -0.2794)
						)
					)
					(width 0)
					(fill yes)
				)
			)
		)
		(pad "2" smd custom
			(at 0 0.4445 270)
			(size 0.1397 0.1397)
			(layers "F.Cu" "F.Mask" "F.Paste")
			(net "FAN_TACH7")
			(options
				(clearance outline)
				(anchor circle)
			)
			(primitives
				(gr_poly
					(pts
						(arc
							(start -0.1778 -0.2794)
							(mid -0.249642 -0.249642)
							(end -0.2794 -0.1778)
						)
						(arc
							(start -0.2794 0.1778)
							(mid -0.249642 0.249642)
							(end -0.1778 0.2794)
						)
						(arc
							(start 0.1778 0.2794)
							(mid 0.249642 0.249642)
							(end 0.2794 0.1778)
						)
						(arc
							(start 0.2794 -0.1778)
							(mid 0.249642 -0.249642)
							(end 0.1778 -0.2794)
						)
					)
					(width 0)
					(fill yes)
				)
			)
		)
	)
	(footprint ""
		(layer "F.Cu")
		(at 26.67 -153.2128 180)
		(property "Reference" "TP1"
			(at 0 0 180)
			(layer "F.SilkS")
			(hide yes)
			(effects
				(font
					(size 1.27 1.27)
				)
			)
		)
		(property "Value" "TPAD32-GP"
			(at 0 -3.166364 180)
			(unlocked yes)
			(layer "F.Fab")
			(hide yes)
			(effects
				(font
					(size 1.016 1.016)
					(thickness 0.1524)
				)
			)
		)
		(property "Device Type" "TPAD32"
			(at 0 -4.690618 180)
			(unlocked yes)
			(layer "F.Fab")
			(hide yes)
			(effects
				(font
					(size 1.016 1.016)
					(thickness 0.1524)
				)
			)
		)
		(duplicate_pad_numbers_are_jumpers no)
		(fp_poly
			(pts
				(arc
					(start -0.7112 0)
					(mid 0.7112 0)
					(end -0.7112 0)
				)
			)
			(stroke
				(width 0)
				(type default)
			)
			(fill no)
			(layer "F.CrtYd")
		)
		(fp_poly
			(pts
				(arc
					(start -0.7112 0)
					(mid 0.7112 0)
					(end -0.7112 0)
				)
			)
			(stroke
				(width 0)
				(type default)
			)
			(fill no)
			(layer "F.Fab")
		)
		(pad "1" smd circle
			(at 0 0 180)
			(size 0.8128 0.8128)
			(layers "F.Cu" "F.Mask" "F.Paste")
			(net "NCT7904_VREF")
		)
	)
	(footprint ""
		(layer "F.Cu")
		(at 26.035 -267.6398 90)
		(property "Reference" "C39"
			(at 0 0 90)
			(layer "F.SilkS")
			(hide yes)
			(effects
				(font
					(size 1.27 1.27)
				)
			)
		)
		(property "Value" "SCD1U50V3KX-GP"
			(at 0 -2.8194 90)
			(unlocked yes)
			(layer "F.Fab")
			(hide yes)
			(effects
				(font
					(size 1.016 1.016)
					(thickness 0.1524)
				)
			)
		)
		(property "Device Type" "C603H36"
			(at 0 -4.3434 90)
			(unlocked yes)
			(layer "F.Fab")
			(hide yes)
			(effects
				(font
					(size 1.016 1.016)
					(thickness 0.1524)
				)
			)
		)
		(duplicate_pad_numbers_are_jumpers no)
		(fp_line
			(start 0.508 0)
			(end -0.508 0)
			(stroke
				(width 0.2032)
				(type default)
			)
			(layer "F.SilkS")
		)
		(fp_rect
			(start -0.5842 1.3335)
			(end 0.5842 -1.3335)
			(stroke
				(width 0)
				(type default)
			)
			(fill no)
			(layer "F.CrtYd")
		)
		(fp_rect
			(start -0.5842 1.3335)
			(end 0.5842 -1.3335)
			(stroke
				(width 0)
				(type default)
			)
			(fill no)
			(layer "F.Fab")
		)
		(pad "1" smd custom
			(at 0 -0.762 90)
			(size 0.2159 0.2159)
			(layers "F.Cu" "F.Mask" "F.Paste")
			(net "P12V")
			(options
				(clearance outline)
				(anchor circle)
			)
			(primitives
				(gr_poly
					(pts
						(arc
							(start -0.3302 -0.4318)
							(mid -0.402042 -0.402042)
							(end -0.4318 -0.3302)
						)
						(arc
							(start -0.4318 0.3302)
							(mid -0.402042 0.402042)
							(end -0.3302 0.4318)
						)
						(arc
							(start 0.3302 0.4318)
							(mid 0.402042 0.402042)
							(end 0.4318 0.3302)
						)
						(arc
							(start 0.4318 -0.3302)
							(mid 0.402042 -0.402042)
							(end 0.3302 -0.4318)
						)
					)
					(width 0)
					(fill yes)
				)
			)
		)
		(pad "2" smd custom
			(at 0 0.762 90)
			(size 0.2159 0.2159)
			(layers "F.Cu" "F.Mask" "F.Paste")
			(net "GND")
			(options
				(clearance outline)
				(anchor circle)
			)
			(primitives
				(gr_poly
					(pts
						(arc
							(start -0.3302 -0.4318)
							(mid -0.402042 -0.402042)
							(end -0.4318 -0.3302)
						)
						(arc
							(start -0.4318 0.3302)
							(mid -0.402042 0.402042)
							(end -0.3302 0.4318)
						)
						(arc
							(start 0.3302 0.4318)
							(mid 0.402042 0.402042)
							(end 0.4318 0.3302)
						)
						(arc
							(start 0.4318 -0.3302)
							(mid 0.402042 -0.402042)
							(end 0.3302 -0.4318)
						)
					)
					(width 0)
					(fill yes)
				)
			)
		)
	)
	(footprint ""
		(layer "F.Cu")
		(at 42.418 -371.221)
		(property "Reference" "PR43"
			(at 0 0 0)
			(layer "F.SilkS")
			(hide yes)
			(effects
				(font
					(size 1.27 1.27)
				)
			)
		)
		(property "Value" "1K5R5J-GP"
			(at 0 -8.9535 0)
			(unlocked yes)
			(layer "F.Fab")
			(hide yes)
			(effects
				(font
					(size 1.27 1.016)
					(thickness 0.1524)
				)
			)
		)
		(property "Device Type" "R805H24"
			(at 0 -10.6299 0)
			(unlocked yes)
			(layer "F.Fab")
			(hide yes)
			(effects
				(font
					(size 1.27 1.016)
					(thickness 0.1524)
				)
			)
		)
		(duplicate_pad_numbers_are_jumpers no)
		(fp_line
			(start -0.889 -1.7018)
			(end -0.889 0.2794)
			(stroke
				(width 0.1524)
				(type default)
			)
			(layer "F.SilkS")
		)
		(fp_line
			(start -0.889 0.0762)
			(end -0.889 1.7018)
			(stroke
				(width 0.1524)
				(type default)
			)
			(layer "F.SilkS")
		)
		(fp_line
			(start -0.889 1.7018)
			(end 0.889 1.7018)
			(stroke
				(width 0.1524)
				(type default)
			)
			(layer "F.SilkS")
		)
		(fp_line
			(start 0.889 -1.7018)
			(end -0.889 -1.7018)
			(stroke
				(width 0.1524)
				(type default)
			)
			(layer "F.SilkS")
		)
		(fp_line
			(start 0.889 -1.7018)
			(end 0.889 -0.381)
			(stroke
				(width 0.1524)
				(type default)
			)
			(layer "F.SilkS")
		)
		(fp_line
			(start 0.889 1.7018)
			(end 0.889 -0.508)
			(stroke
				(width 0.1524)
				(type default)
			)
			(layer "F.SilkS")
		)
		(fp_poly
			(pts
				(xy 0.9652 -1.778) (xy 0.9652 1.778) (xy -0.9652 1.778) (xy -0.9652 -1.778)
			)
			(stroke
				(width 0)
				(type default)
			)
			(fill no)
			(layer "F.CrtYd")
		)
		(fp_rect
			(start -0.9652 1.778)
			(end 0.9652 -1.778)
			(stroke
				(width 0)
				(type default)
			)
			(fill no)
			(layer "F.Fab")
		)
		(pad "1" smd rect
			(at 0 -0.9652)
			(size 1.397 1.143)
			(layers "F.Cu" "F.Mask" "F.Paste")
			(net "P12V_AUX")
		)
		(pad "2" smd rect
			(at 0 0.9652)
			(size 1.397 1.143)
			(layers "F.Cu" "F.Mask" "F.Paste")
			(net "ADM1276_EN_NET")
		)
	)
	(footprint ""
		(layer "F.Cu")
		(at 26.8732 -357.6574 -90)
		(property "Reference" "R367"
			(at 0 0 270)
			(layer "F.SilkS")
			(hide yes)
			(effects
				(font
					(size 1.27 1.27)
				)
			)
		)
		(property "Value" "10KR2F-2-GP"
			(at 0.064008 -3.993896 270)
			(unlocked yes)
			(layer "F.Fab")
			(hide yes)
			(effects
				(font
					(size 1.016 1.016)
					(thickness 0.1524)
				)
			)
		)
		(property "Device Type" "R402H16"
			(at 0.064008 -5.517896 270)
			(unlocked yes)
			(layer "F.Fab")
			(hide yes)
			(effects
				(font
					(size 1.016 1.016)
					(thickness 0.1524)
				)
			)
		)
		(duplicate_pad_numbers_are_jumpers no)
		(fp_line
			(start -0.508 -0.9398)
			(end -0.508 0.9398)
			(stroke
				(width 0.1524)
				(type default)
			)
			(layer "F.SilkS")
		)
		(fp_line
			(start 0.508 -0.9398)
			(end -0.508 -0.9398)
			(stroke
				(width 0.1524)
				(type default)
			)
			(layer "F.SilkS")
		)
		(fp_rect
			(start -0.508 0.9398)
			(end 0.508 -0.9398)
			(stroke
				(width 0)
				(type default)
			)
			(fill no)
			(layer "F.CrtYd")
		)
		(fp_rect
			(start -0.508 0.9398)
			(end 0.508 -0.9398)
			(stroke
				(width 0)
				(type default)
			)
			(fill no)
			(layer "F.Fab")
		)
		(pad "1" smd custom
			(at 0 -0.4445 270)
			(size 0.1397 0.1397)
			(layers "F.Cu" "F.Mask" "F.Paste")
			(net "P3V3")
			(options
				(clearance outline)
				(anchor circle)
			)
			(primitives
				(gr_poly
					(pts
						(arc
							(start -0.1778 -0.2794)
							(mid -0.249642 -0.249642)
							(end -0.2794 -0.1778)
						)
						(arc
							(start -0.2794 0.1778)
							(mid -0.249642 0.249642)
							(end -0.1778 0.2794)
						)
						(arc
							(start 0.1778 0.2794)
							(mid 0.249642 0.249642)
							(end 0.2794 0.1778)
						)
						(arc
							(start 0.2794 -0.1778)
							(mid 0.249642 -0.249642)
							(end 0.1778 -0.2794)
						)
					)
					(width 0)
					(fill yes)
				)
			)
		)
		(pad "2" smd custom
			(at 0 0.4445 270)
			(size 0.1397 0.1397)
			(layers "F.Cu" "F.Mask" "F.Paste")
			(net "TEMP_ALM#_G")
			(options
				(clearance outline)
				(anchor circle)
			)
			(primitives
				(gr_poly
					(pts
						(arc
							(start -0.1778 -0.2794)
							(mid -0.249642 -0.249642)
							(end -0.2794 -0.1778)
						)
						(arc
							(start -0.2794 0.1778)
							(mid -0.249642 0.249642)
							(end -0.1778 0.2794)
						)
						(arc
							(start 0.1778 0.2794)
							(mid 0.249642 0.249642)
							(end 0.2794 0.1778)
						)
						(arc
							(start 0.2794 -0.1778)
							(mid 0.249642 -0.249642)
							(end 0.1778 -0.2794)
						)
					)
					(width 0)
					(fill yes)
				)
			)
		)
	)
	(footprint ""
		(layer "F.Cu")
		(at 35.59429 -150.680166 180)
		(property "Reference" "TP11"
			(at 0 0 180)
			(layer "F.SilkS")
			(hide yes)
			(effects
				(font
					(size 1.27 1.27)
				)
			)
		)
		(property "Value" "TPAD32-GP"
			(at 0 -3.166364 180)
			(unlocked yes)
			(layer "F.Fab")
			(hide yes)
			(effects
				(font
					(size 1.016 1.016)
					(thickness 0.1524)
				)
			)
		)
		(property "Device Type" "TPAD32"
			(at 0 -4.690618 180)
			(unlocked yes)
			(layer "F.Fab")
			(hide yes)
			(effects
				(font
					(size 1.016 1.016)
					(thickness 0.1524)
				)
			)
		)
		(duplicate_pad_numbers_are_jumpers no)
		(fp_poly
			(pts
				(arc
					(start 0.7112 0)
					(mid -0.7112 0)
					(end 0.7112 0)
				)
			)
			(stroke
				(width 0)
				(type default)
			)
			(fill no)
			(layer "F.CrtYd")
		)
		(fp_poly
			(pts
				(arc
					(start 0.7112 0)
					(mid -0.7112 0)
					(end 0.7112 0)
				)
			)
			(stroke
				(width 0)
				(type default)
			)
			(fill no)
			(layer "F.Fab")
		)
		(pad "1" smd circle
			(at 0 0 180)
			(size 0.8128 0.8128)
			(layers "F.Cu" "F.Mask" "F.Paste")
			(net "NCT7904_VSEN12")
		)
	)
	(footprint ""
		(layer "F.Cu")
		(at 14.8844 -43.5102 -90)
		(property "Reference" "R118"
			(at 0 0 270)
			(layer "F.SilkS")
			(hide yes)
			(effects
				(font
					(size 1.27 1.27)
				)
			)
		)
		(property "Value" "470R2F-GP"
			(at 0.064008 -3.993896 270)
			(unlocked yes)
			(layer "F.Fab")
			(hide yes)
			(effects
				(font
					(size 1.016 1.016)
					(thickness 0.1524)
				)
			)
		)
		(property "Device Type" "R402H16"
			(at 0.064008 -5.517896 270)
			(unlocked yes)
			(layer "F.Fab")
			(hide yes)
			(effects
				(font
					(size 1.016 1.016)
					(thickness 0.1524)
				)
			)
		)
		(duplicate_pad_numbers_are_jumpers no)
		(fp_line
			(start -0.508 -0.9398)
			(end -0.508 0.9398)
			(stroke
				(width 0.1524)
				(type default)
			)
			(layer "F.SilkS")
		)
		(fp_line
			(start 0.508 -0.9398)
			(end -0.508 -0.9398)
			(stroke
				(width 0.1524)
				(type default)
			)
			(layer "F.SilkS")
		)
		(fp_rect
			(start -0.508 0.9398)
			(end 0.508 -0.9398)
			(stroke
				(width 0)
				(type default)
			)
			(fill no)
			(layer "F.CrtYd")
		)
		(fp_rect
			(start -0.508 0.9398)
			(end 0.508 -0.9398)
			(stroke
				(width 0)
				(type default)
			)
			(fill no)
			(layer "F.Fab")
		)
		(pad "1" smd custom
			(at 0 -0.4445 270)
			(size 0.1397 0.1397)
			(layers "F.Cu" "F.Mask" "F.Paste")
			(net "SEB_PEER_2A_HB")
			(options
				(clearance outline)
				(anchor circle)
			)
			(primitives
				(gr_poly
					(pts
						(arc
							(start -0.1778 -0.2794)
							(mid -0.249642 -0.249642)
							(end -0.2794 -0.1778)
						)
						(arc
							(start -0.2794 0.1778)
							(mid -0.249642 0.249642)
							(end -0.1778 0.2794)
						)
						(arc
							(start 0.1778 0.2794)
							(mid 0.249642 0.249642)
							(end 0.2794 0.1778)
						)
						(arc
							(start 0.2794 -0.1778)
							(mid 0.249642 -0.249642)
							(end 0.1778 -0.2794)
						)
					)
					(width 0)
					(fill yes)
				)
			)
		)
		(pad "2" smd custom
			(at 0 0.4445 270)
			(size 0.1397 0.1397)
			(layers "F.Cu" "F.Mask" "F.Paste")
			(net "GND")
			(options
				(clearance outline)
				(anchor circle)
			)
			(primitives
				(gr_poly
					(pts
						(arc
							(start -0.1778 -0.2794)
							(mid -0.249642 -0.249642)
							(end -0.2794 -0.1778)
						)
						(arc
							(start -0.2794 0.1778)
							(mid -0.249642 0.249642)
							(end -0.1778 0.2794)
						)
						(arc
							(start 0.1778 0.2794)
							(mid 0.249642 0.249642)
							(end 0.2794 0.1778)
						)
						(arc
							(start 0.2794 -0.1778)
							(mid 0.249642 -0.249642)
							(end 0.1778 -0.2794)
						)
					)
					(width 0)
					(fill yes)
				)
			)
		)
	)
)
